.HEADER
BOARD_FILE 3.0 "Creo Elements/Pro 5.0 M210" 2017/03/01.13:12:19 3
16318-SB                                MM        
.END_HEADER
.BOARD_OUTLINE  MCAD
1.60000             
         0           235.00000             1.00000             0.00000
         0           235.00000           183.76393             0.00000
         0           234.89443           184.21115            26.56505
         0           230.27639           193.44721             0.00000
         0           229.38197           194.00000            63.43495
         0           149.91803           194.00000             0.00000
         0           149.02361           193.44721            63.43495
         0           144.40557           184.21115             0.00000
         0           144.30000           183.76393            26.56505
         0           144.30000            48.00000             0.00000
         0           143.30000            48.00000          -180.00000
         0           104.70000            48.00000             0.00000
         0           103.70000            48.00000          -180.00000
         0           103.70000           183.76393             0.00000
         0           103.59443           184.21115            26.56505
         0            98.97639           193.44721             0.00000
         0            98.08197           194.00000            63.43495
         0             5.61803           194.00000             0.00000
         0             4.72361           193.44721            63.43495
         0             0.10557           184.21115             0.00000
         0             0.00000           183.76393            26.56505
         0             0.00000             1.00000             0.00000
         0             1.00000             0.00000            90.00000
         0            29.53000            -0.00000             0.00000
         0            30.53000             1.00000            90.00000
         0            30.53000           109.05000             0.00000
         0            31.53000           110.05000           -90.00000
         0            72.03000           110.05000             0.00000
         0            73.03000           109.05000           -90.00000
         0            73.03000             1.00000             0.00000
         0            74.03000             0.00000            90.00000
         0           234.00000            -0.00000             0.00000
         0           235.00000             1.00000            90.00000
         1            80.25000           103.35000             0.00000
         1            76.85000           103.35000             0.00000
         1            76.85000           106.75000          -180.00000
         1            80.25000           106.75000             0.00000
         1            80.25000           103.35000          -180.00000
         2            24.50000            58.85000             0.00000
         2            21.10000            58.85000             0.00000
         2            21.10000            62.25000          -180.00000
         2            24.50000            62.25000             0.00000
         2            24.50000            58.85000          -180.00000
         3           167.30000            45.72000             0.00000
         3           164.30000            45.72000          -180.00000
         3           167.30000            45.72000          -180.00000
         4           221.30000            84.48000             0.00000
         4           218.30000            84.48000          -180.00000
         4           221.30000            84.48000          -180.00000
         5           125.44010            34.85500             0.00000
         5           122.89010            34.85500          -180.00000
         5           125.44010            34.85500          -180.00000
         6           125.37010            41.84500             0.00000
         6           122.96010            41.84500          -180.00000
         6           125.37010            41.84500          -180.00000
         7            19.75000            25.00000             0.00000
         7            16.25000            25.00000          -180.00000
         7            19.75000            25.00000          -180.00000
         8            14.50000           188.00000             0.00000
         8            10.50000           188.00000          -180.00000
         8            14.50000           188.00000          -180.00000
         9           224.25000           188.00000             0.00000
         9           220.75000           188.00000          -180.00000
         9           224.25000           188.00000          -180.00000
        10           224.50000            15.00000             0.00000
        10           220.50000            15.00000          -180.00000
        10           224.50000            15.00000          -180.00000
        11            81.75000           120.00000             0.00000
        11            78.25000           120.00000          -180.00000
        11            81.75000           120.00000          -180.00000
        12            94.25000           188.00000             0.00000
        12            90.75000           188.00000          -180.00000
        12            94.25000           188.00000          -180.00000
        13           157.25000           188.00000             0.00000
        13           153.75000           188.00000          -180.00000
        13           157.25000           188.00000          -180.00000
        14           104.75000            10.00000             0.00000
        14           101.25000            10.00000          -180.00000
        14           104.75000            10.00000          -180.00000
        15            19.75000           120.00000             0.00000
        15            16.25000           120.00000          -180.00000
        15            19.75000           120.00000          -180.00000
        16           157.25000           110.00000             0.00000
        16           153.75000           110.00000          -180.00000
        16           157.25000           110.00000          -180.00000
        17           224.25000           110.00000             0.00000
        17           220.75000           110.00000          -180.00000
        17           224.25000           110.00000          -180.00000
        18           161.10000            14.70000             0.00000
        18           158.90000            14.70000          -180.00000
        18           161.10000            14.70000          -180.00000
        19           181.10000            14.70000             0.00000
        19           178.90000            14.70000          -180.00000
        19           181.10000            14.70000          -180.00000
        20            43.55000           170.00000             0.00000
        20            39.35000           170.00000          -180.00000
        20            43.55000           170.00000          -180.00000
        21            80.15000            40.05000             0.00000
        21            76.85000            40.05000          -180.00000
        21            80.15000            40.05000          -180.00000
        22            24.55000           105.05000             0.00000
        22            21.25000           105.05000          -180.00000
        22            24.55000           105.05000          -180.00000
.END_BOARD_OUTLINE
.DRILLED_HOLES
.END_DRILLED_HOLES
.PLACE_KEEPOUT      UNOWNED
TOP 0.00000        
         0           150.75000           188.00000             0.00000
         0           160.25000           188.00000           180.00000
         0           150.75000           188.00000           180.00000
.END_PLACE_KEEPOUT
.PLACE_KEEPOUT      UNOWNED
TOP 0.00000        
         0           217.75000           188.00000             0.00000
         0           227.25000           188.00000           180.00000
         0           217.75000           188.00000           180.00000
.END_PLACE_KEEPOUT
.PLACE_KEEPOUT      UNOWNED
TOP 0.00000        
         0           107.75000            10.00000             0.00000
         0            98.25000            10.00000           180.00000
         0           107.75000            10.00000           180.00000
.END_PLACE_KEEPOUT
.PLACE_KEEPOUT      UNOWNED
TOP 0.00000        
         0            78.50000            44.80000             0.00000
         0            78.50000            35.30000           180.00000
         0            89.50000            35.30000             0.00000
         0            89.50000            44.80000             0.00000
         0            78.50000            44.80000             0.00000
.END_PLACE_KEEPOUT
.PLACE_KEEPOUT      UNOWNED
TOP 0.00000        
         0           217.75000            15.00000             0.00000
         0           227.25000            15.00000           180.00000
         0           217.75000            15.00000           180.00000
.END_PLACE_KEEPOUT
.PLACE_KEEPOUT      UNOWNED
TOP 0.00000        
         0            13.25000            25.00000             0.00000
         0            22.75000            25.00000           180.00000
         0            13.25000            25.00000           180.00000
.END_PLACE_KEEPOUT
.PLACE_KEEPOUT      UNOWNED
TOP 0.00000        
         0            22.80000            55.80000             0.00000
         0             8.65000            55.80000             0.00000
         0             8.65000            65.30000             0.00000
         0            22.80000            65.30000             0.00000
         0            22.80000            55.80000          -180.00000
.END_PLACE_KEEPOUT
.PLACE_KEEPOUT      UNOWNED
TOP 0.00000        
         0            11.90000           109.80000             0.00000
         0            11.90000           103.80000             0.00000
         0            18.31742           103.80000             0.00000
         0            22.90000           109.80000           254.74248
         0            11.90000           109.80000             0.00000
.END_PLACE_KEEPOUT
.PLACE_KEEPOUT      UNOWNED
TOP 0.00000        
         0             7.75000           188.00000             0.00000
         0            17.25000           188.00000           180.00000
         0             7.75000           188.00000           180.00000
.END_PLACE_KEEPOUT
.PLACE_KEEPOUT      UNOWNED
TOP 0.00000        
         0            37.70000           170.00000             0.00000
         0            45.20000           170.00000           180.00000
         0            37.70000           170.00000           180.00000
.END_PLACE_KEEPOUT
.PLACE_KEEPOUT      UNOWNED
TOP 0.00000        
         0            87.75000           188.00000             0.00000
         0            97.25000           188.00000           180.00000
         0            87.75000           188.00000           180.00000
.END_PLACE_KEEPOUT
.PLACE_KEEPOUT      UNOWNED
TOP 0.00000        
         0            75.25000           120.00000             0.00000
         0            84.75000           120.00000           180.00000
         0            75.25000           120.00000           180.00000
.END_PLACE_KEEPOUT
.PLACE_KEEPOUT      UNOWNED
TOP 0.00000        
         0            78.55000           109.80000             0.00000
         0            78.55000           100.30000           180.00000
         0            92.70000           100.30000             0.00000
         0            92.70000           109.80000             0.00000
         0            78.55000           109.80000             0.00000
.END_PLACE_KEEPOUT
.PLACE_KEEPOUT      UNOWNED
TOP 0.00000        
         0           216.80000            84.48000             0.00000
         0           222.80000            84.48000           180.00000
         0           216.80000            84.48000           180.00000
.END_PLACE_KEEPOUT
.PLACE_KEEPOUT      UNOWNED
TOP 0.00000        
         0           162.80000            45.72000             0.00000
         0           168.80000            45.72000           180.00000
         0           162.80000            45.72000           180.00000
.END_PLACE_KEEPOUT
.PLACE_KEEPOUT      UNOWNED
TOP 0.00000        
         0           150.75000           110.00000             0.00000
         0           160.25000           110.00000           180.00000
         0           150.75000           110.00000           180.00000
.END_PLACE_KEEPOUT
.PLACE_KEEPOUT      UNOWNED
TOP 0.00000        
         0           217.75000           110.00000             0.00000
         0           227.25000           110.00000           180.00000
         0           217.75000           110.00000           180.00000
.END_PLACE_KEEPOUT
.PLACE_KEEPOUT      UNOWNED
TOP 0.00000        
         0            13.25000           120.00000             0.00000
         0            22.75000           120.00000           180.00000
         0            13.25000           120.00000           180.00000
.END_PLACE_KEEPOUT
.PLACE_KEEPOUT      UNOWNED
TOP 0.00000        
         0           230.00000            -0.00000             0.00000
         0           234.00000            -0.00000             0.00000
         0           235.00000             1.00000            90.00000
         0           235.00000           183.76393             0.00000
         0           234.89443           184.21115            26.56505
         0           230.27639           193.44721             0.00000
         0           230.00000           193.78615            25.26224
         0           230.00000            -0.00000             0.00000
.END_PLACE_KEEPOUT
.PLACE_KEEPOUT      UNOWNED
TOP 0.00000        
         0             1.00000            -0.00000             0.00000
         0             5.00000            -0.00000             0.00000
         0             5.00000           193.78615             0.00000
         0             4.72361           193.44721            25.26224
         0             0.10557           184.21115             0.00000
         0             0.00000           183.76393            26.56505
         0             0.00000             1.00000             0.00000
         0             1.00000             0.00000            90.00000
.END_PLACE_KEEPOUT
.PLACE_KEEPOUT      UNOWNED
TOP 0.50000        
         0           161.80000            34.10000             0.00000
         0           223.80000            34.10000             0.00000
         0           223.80000            96.10000             0.00000
         0           161.80000            96.10000             0.00000
         0           161.80000            34.10000             0.00000
.END_PLACE_KEEPOUT
.PLACE_KEEPOUT      UNOWNED
TOP 0.50000        
         0           222.80000            84.48000             0.00000
         0           216.80000            84.48000           180.00000
         0           222.80000            84.48000           180.00000
.END_PLACE_KEEPOUT
.PLACE_KEEPOUT      UNOWNED
TOP 0.50000        
         0           168.80000            45.72000             0.00000
         0           162.80000            45.72000           180.00000
         0           168.80000            45.72000           180.00000
.END_PLACE_KEEPOUT
.PLACE_KEEPOUT      UNOWNED
TOP 0.00000        
         0            73.03000             1.00000             0.00000
         0            74.03000             0.00000            90.00000
         0            82.30000            -0.00000             0.00000
         0            82.30000            29.20000             0.00000
         0            85.70000            29.20000             0.00000
         0            85.70000            35.30000             0.00000
         0            78.50000            35.30000             0.00000
         0            78.50000            44.80000          -180.00000
         0            85.70000            44.80000             0.00000
         0            85.70000           100.30000             0.00000
         0            78.55000           100.30000             0.00000
         0            78.55000           109.80000          -180.00000
         0            85.70000           109.80000             0.00000
         0            85.70000           113.05000             0.00000
         0             6.70000           113.05000             0.00000
         0             6.70000           109.80000             0.00000
         0            22.90000           109.80000             0.00000
         0            18.31742           103.80000          -254.74248
         0             6.70000           103.80000             0.00000
         0             6.70000            65.30000             0.00000
         0            22.80000            65.30000             0.00000
         0            22.80000            55.80000          -180.00000
         0             6.70000            55.80000             0.00000
         0             6.70000            48.60000             0.00000
         0            30.53000            48.60000             0.00000
         0            30.53000           109.05000             0.00000
         0            31.53000           110.05000           -90.00000
         0            72.03000           110.05000             0.00000
         0            73.03000           109.05000           -90.00000
         0            73.03000             1.00000             0.00000
.END_PLACE_KEEPOUT
.PLACE_KEEPOUT      UNOWNED
TOP 6.00000        
         0            29.50000            32.00000             0.00000
         0             5.50000            32.00000             0.00000
         0             5.50000            44.00000             0.00000
         0            29.50000            44.00000             0.00000
         0            29.50000            32.00000             0.00000
.END_PLACE_KEEPOUT
.PLACE_KEEPOUT      UNOWNED
TOP 9.30000        
         0            73.43000           113.20000             0.00000
         0            24.60000           113.20000             0.00000
         0            24.60000           129.52000             0.00000
         0            73.43000           129.52000             0.00000
         0            73.43000           113.20000             0.00000
.END_PLACE_KEEPOUT
.PLACE_KEEPOUT      UNOWNED
TOP 4.00000        
         0           161.80000            34.10000             0.00000
         0           161.80000            96.10000             0.00000
         0           223.80000            96.10000             0.00000
         0           223.80000            34.10000             0.00000
         0           161.80000            34.10000             0.00000
.END_PLACE_KEEPOUT
.PLACE_KEEPOUT      UNOWNED
TOP 4.00000        
         0             5.00000            -0.00000             0.00000
         0            29.53000            -0.00000             0.00000
         0            30.53000             1.00000            90.00000
         0            30.53000            32.00000             0.00000
         0            29.50000            32.00000             0.00000
         0             5.50000            32.00000             0.00000
         0             5.50000            44.00000             0.00000
         0            29.50000            44.00000             0.00000
         0            29.50000            32.10000             0.00000
         0            30.53000            32.10000             0.00000
         0            30.53000            48.60000             0.00000
         0             6.70000            48.60000             0.00000
         0             6.70000            55.80000             0.00000
         0             8.65000            55.80000             0.00000
         0             8.65000            65.30000             0.00000
         0             6.70000            65.30000             0.00000
         0             6.70000           103.80000             0.00000
         0            11.90000           103.80000             0.00000
         0            11.90000           109.80000             0.00000
         0             6.70000           109.80000             0.00000
         0             6.70000           113.05000             0.00000
         0            85.70000           113.05000             0.00000
         0            85.70000           109.80000             0.00000
         0            92.70000           109.80000             0.00000
         0            92.70000           100.30000             0.00000
         0            85.70000           100.30000             0.00000
         0            85.70000            44.80000             0.00000
         0            89.50000            44.80000             0.00000
         0            89.50000            35.30000             0.00000
         0            85.70000            35.30000             0.00000
         0            85.70000            29.20000             0.00000
         0            82.30000            29.20000             0.00000
         0            82.30000            -0.00000             0.00000
         0           230.00000            -0.00000             0.00000
         0           230.00000           193.78615             0.00000
         0           229.38197           194.00000            38.17271
         0           149.91803           194.00000             0.00000
         0           149.02361           193.44721            63.43495
         0           144.40557           184.21115             0.00000
         0           144.30000           183.76393            26.56505
         0           144.30000            48.00000             0.00000
         0           143.30000            48.00000          -180.00000
         0           104.70000            48.00000             0.00000
         0           103.70000            48.00000          -180.00000
         0           103.70000           129.42000             0.00000
         0            73.43000           129.42000             0.00000
         0            73.43000           113.20000             0.00000
         0            24.60000           113.20000             0.00000
         0            24.60000           129.52000             0.00000
         0            73.43000           129.52000             0.00000
         0           103.70000           129.52000             0.00000
         0           103.70000           183.76393             0.00000
         0           103.59443           184.21115            26.56505
         0            98.97639           193.44721             0.00000
         0            98.08197           194.00000            63.43495
         0             5.61803           194.00000             0.00000
         0             5.00000           193.78615            38.17271
         0             5.00000            -0.00000             0.00000
.END_PLACE_KEEPOUT
.PLACE_KEEPOUT      UNOWNED
TOP 4.00000        
         0            17.25000           188.00000             0.00000
         0             7.75000           188.00000           180.00000
         0            17.25000           188.00000           180.00000
.END_PLACE_KEEPOUT
.PLACE_KEEPOUT      UNOWNED
TOP 4.00000        
         0            45.20000           170.00000             0.00000
         0            37.70000           170.00000           180.00000
         0            45.20000           170.00000           180.00000
.END_PLACE_KEEPOUT
.PLACE_KEEPOUT      UNOWNED
TOP 4.00000        
         0            84.75000           120.00000             0.00000
         0            75.25000           120.00000           180.00000
         0            84.75000           120.00000           180.00000
.END_PLACE_KEEPOUT
.PLACE_KEEPOUT      UNOWNED
TOP 4.00000        
         0            22.75000           120.00000             0.00000
         0            13.25000           120.00000           180.00000
         0            22.75000           120.00000           180.00000
.END_PLACE_KEEPOUT
.PLACE_KEEPOUT      UNOWNED
TOP 4.00000        
         0            22.75000            25.00000             0.00000
         0            13.25000            25.00000           180.00000
         0            22.75000            25.00000           180.00000
.END_PLACE_KEEPOUT
.PLACE_KEEPOUT      UNOWNED
TOP 4.00000        
         0           227.25000            15.00000             0.00000
         0           217.75000            15.00000           180.00000
         0           227.25000            15.00000           180.00000
.END_PLACE_KEEPOUT
.PLACE_KEEPOUT      UNOWNED
TOP 4.00000        
         0           107.75000            10.00000             0.00000
         0            98.25000            10.00000           180.00000
         0           107.75000            10.00000           180.00000
.END_PLACE_KEEPOUT
.PLACE_KEEPOUT      UNOWNED
TOP 4.00000        
         0           160.25000           188.00000             0.00000
         0           150.75000           188.00000           180.00000
         0           160.25000           188.00000           180.00000
.END_PLACE_KEEPOUT
.PLACE_KEEPOUT      UNOWNED
TOP 4.00000        
         0           227.25000           188.00000             0.00000
         0           217.75000           188.00000           180.00000
         0           227.25000           188.00000           180.00000
.END_PLACE_KEEPOUT
.PLACE_KEEPOUT      UNOWNED
TOP 4.00000        
         0           160.25000           110.00000             0.00000
         0           150.75000           110.00000           180.00000
         0           160.25000           110.00000           180.00000
.END_PLACE_KEEPOUT
.PLACE_KEEPOUT      UNOWNED
TOP 4.00000        
         0           227.25000           110.00000             0.00000
         0           217.75000           110.00000           180.00000
         0           227.25000           110.00000           180.00000
.END_PLACE_KEEPOUT
.PLACE_KEEPOUT      UNOWNED
TOP 4.00000        
         0            97.25000           188.00000             0.00000
         0            87.75000           188.00000           180.00000
         0            97.25000           188.00000           180.00000
.END_PLACE_KEEPOUT
.PLACE_KEEPOUT      UNOWNED
BOTTOM 0.00000        
         0            97.25000           188.00000             0.00000
         0            87.75000           188.00000          -180.00000
         0            97.25000           188.00000          -180.00000
.END_PLACE_KEEPOUT
.PLACE_KEEPOUT      UNOWNED
BOTTOM 0.00000        
         0            17.25000           188.00000             0.00000
         0             7.75000           188.00000          -180.00000
         0            17.25000           188.00000          -180.00000
.END_PLACE_KEEPOUT
.PLACE_KEEPOUT      UNOWNED
BOTTOM 0.00000        
         0            84.75000           120.00000             0.00000
         0            75.25000           120.00000          -180.00000
         0            84.75000           120.00000          -180.00000
.END_PLACE_KEEPOUT
.PLACE_KEEPOUT      UNOWNED
BOTTOM 0.00000        
         0            83.30000           105.05000             0.00000
         0            73.80000           105.05000          -180.00000
         0            83.30000           105.05000          -180.00000
.END_PLACE_KEEPOUT
.PLACE_KEEPOUT      UNOWNED
BOTTOM 0.00000        
         0            27.65000           105.05000             0.00000
         0            18.15000           105.05000          -180.00000
         0            27.65000           105.05000          -180.00000
.END_PLACE_KEEPOUT
.PLACE_KEEPOUT      UNOWNED
BOTTOM 0.00000        
         0            83.25000            40.05000             0.00000
         0            73.75000            40.05000          -180.00000
         0            83.25000            40.05000          -180.00000
.END_PLACE_KEEPOUT
.PLACE_KEEPOUT      UNOWNED
BOTTOM 0.00000        
         0            27.55000            60.55000             0.00000
         0            18.05000            60.55000          -180.00000
         0            27.55000            60.55000          -180.00000
.END_PLACE_KEEPOUT
.PLACE_KEEPOUT      UNOWNED
BOTTOM 0.00000        
         0            22.75000            25.00000             0.00000
         0            13.25000            25.00000          -180.00000
         0            22.75000            25.00000          -180.00000
.END_PLACE_KEEPOUT
.PLACE_KEEPOUT      UNOWNED
BOTTOM 0.00000        
         0           107.75000            10.00000             0.00000
         0            98.25000            10.00000          -180.00000
         0           107.75000            10.00000          -180.00000
.END_PLACE_KEEPOUT
.PLACE_KEEPOUT      UNOWNED
BOTTOM 0.00000        
         0           126.66510            34.85500             0.00000
         0           121.66510            34.85500          -180.00000
         0           126.66510            34.85500          -180.00000
.END_PLACE_KEEPOUT
.PLACE_KEEPOUT      UNOWNED
BOTTOM 0.00000        
         0           162.50000            14.70000             0.00000
         0           157.50000            14.70000          -180.00000
         0           162.50000            14.70000          -180.00000
.END_PLACE_KEEPOUT
.PLACE_KEEPOUT      UNOWNED
BOTTOM 0.00000        
         0           182.50000            14.70000             0.00000
         0           177.50000            14.70000          -180.00000
         0           182.50000            14.70000          -180.00000
.END_PLACE_KEEPOUT
.PLACE_KEEPOUT      UNOWNED
BOTTOM 0.00000        
         0           227.25000            15.00000             0.00000
         0           217.75000            15.00000          -180.00000
         0           227.25000            15.00000          -180.00000
.END_PLACE_KEEPOUT
.PLACE_KEEPOUT      UNOWNED
BOTTOM 0.00000        
         0           227.25000           188.00000             0.00000
         0           217.75000           188.00000          -180.00000
         0           227.25000           188.00000          -180.00000
.END_PLACE_KEEPOUT
.PLACE_KEEPOUT      UNOWNED
BOTTOM 0.00000        
         0           160.25000           188.00000             0.00000
         0           150.75000           188.00000          -180.00000
         0           160.25000           188.00000          -180.00000
.END_PLACE_KEEPOUT
.PLACE_KEEPOUT      UNOWNED
BOTTOM 0.00000        
         0            45.20000           170.00000             0.00000
         0            37.70000           170.00000          -180.00000
         0            45.20000           170.00000          -180.00000
.END_PLACE_KEEPOUT
.PLACE_KEEPOUT      UNOWNED
BOTTOM 0.00000        
         0           168.80000            45.72000             0.00000
         0           162.80000            45.72000          -180.00000
         0           168.80000            45.72000          -180.00000
.END_PLACE_KEEPOUT
.PLACE_KEEPOUT      UNOWNED
BOTTOM 0.00000        
         0           222.80000            84.48000             0.00000
         0           216.80000            84.48000          -180.00000
         0           222.80000            84.48000          -180.00000
.END_PLACE_KEEPOUT
.PLACE_KEEPOUT      UNOWNED
BOTTOM 0.00000        
         0            13.25000           120.00000             0.00000
         0            22.75000           120.00000          -180.00000
         0            13.25000           120.00000          -180.00000
.END_PLACE_KEEPOUT
.PLACE_KEEPOUT      UNOWNED
BOTTOM 0.00000        
         0           227.25000           110.00000             0.00000
         0           217.75000           110.00000          -180.00000
         0           227.25000           110.00000          -180.00000
.END_PLACE_KEEPOUT
.PLACE_KEEPOUT      UNOWNED
BOTTOM 0.00000        
         0           160.25000           110.00000             0.00000
         0           150.75000           110.00000          -180.00000
         0           160.25000           110.00000          -180.00000
.END_PLACE_KEEPOUT
.PLACE_KEEPOUT      UNOWNED
BOTTOM 0.00000        
         0             1.00000             0.00000             0.00000
         0             0.00000             1.00000           -90.00000
         0             0.00000           183.76393             0.00000
         0             0.10557           184.21115           -26.56505
         0             4.72361           193.44721             0.00000
         0             5.00000           193.78615           -25.26224
         0             5.00000            -0.00000             0.00000
         0             1.00000            -0.00000             0.00000
.END_PLACE_KEEPOUT
.PLACE_KEEPOUT      UNOWNED
BOTTOM 0.00000        
         0           230.00000           193.78615             0.00000
         0           230.00000            -0.00000             0.00000
         0           234.00000            -0.00000             0.00000
         0           235.00000             1.00000            90.00000
         0           235.00000           183.76393             0.00000
         0           234.89443           184.21115            26.56505
         0           230.27639           193.44721             0.00000
         0           230.00000           193.78615            25.26224
.END_PLACE_KEEPOUT
.PLACE_KEEPOUT      UNOWNED
BOTTOM 2.00000        
         0            72.03000           110.05000             0.00000
         0            31.53000           110.05000             0.00000
         0            30.53000           109.05000            90.00000
         0            30.53000             1.00000             0.00000
         0            29.53000             0.00000           -90.00000
         0             5.00000            -0.00000             0.00000
         0             5.00000           193.78615             0.00000
         0             5.61803           194.00000           -38.17271
         0            98.08197           194.00000             0.00000
         0            98.97639           193.44721           -63.43495
         0           103.59443           184.21115             0.00000
         0           103.70000           183.76393           -26.56505
         0           103.70000            48.00000             0.00000
         0           104.70000            48.00000           180.00000
         0           143.30000            48.00000             0.00000
         0           144.30000            48.00000           180.00000
         0           144.30000           183.76393             0.00000
         0           144.40557           184.21115           -26.56505
         0           149.02361           193.44721             0.00000
         0           149.91803           194.00000           -63.43495
         0           229.38197           194.00000             0.00000
         0           230.00000           193.78615           -38.17271
         0           230.00000            -0.00000             0.00000
         0            74.03000            -0.00000             0.00000
         0            73.03000             1.00000           -90.00000
         0            73.03000           109.05000             0.00000
         0            72.03000           110.05000            90.00000
.END_PLACE_KEEPOUT
.PLACE_KEEPOUT      UNOWNED
BOTTOM 2.00000        
         0           217.75000            15.00000             0.00000
         0           227.25000            15.00000          -180.00000
         0           217.75000            15.00000          -180.00000
.END_PLACE_KEEPOUT
.PLACE_KEEPOUT      UNOWNED
BOTTOM 2.00000        
         0           177.50000            14.70000             0.00000
         0           182.50000            14.70000          -180.00000
         0           177.50000            14.70000          -180.00000
.END_PLACE_KEEPOUT
.PLACE_KEEPOUT      UNOWNED
BOTTOM 2.00000        
         0           157.50000            14.70000             0.00000
         0           162.50000            14.70000          -180.00000
         0           157.50000            14.70000          -180.00000
.END_PLACE_KEEPOUT
.PLACE_KEEPOUT      UNOWNED
BOTTOM 2.00000        
         0           217.75000           188.00000             0.00000
         0           227.25000           188.00000          -180.00000
         0           217.75000           188.00000          -180.00000
.END_PLACE_KEEPOUT
.PLACE_KEEPOUT      UNOWNED
BOTTOM 2.00000        
         0           150.75000           188.00000             0.00000
         0           160.25000           188.00000          -180.00000
         0           150.75000           188.00000          -180.00000
.END_PLACE_KEEPOUT
.PLACE_KEEPOUT      UNOWNED
BOTTOM 2.00000        
         0            87.75000           188.00000             0.00000
         0            97.25000           188.00000          -180.00000
         0            87.75000           188.00000          -180.00000
.END_PLACE_KEEPOUT
.PLACE_KEEPOUT      UNOWNED
BOTTOM 2.00000        
         0             7.75000           188.00000             0.00000
         0            17.25000           188.00000          -180.00000
         0             7.75000           188.00000          -180.00000
.END_PLACE_KEEPOUT
.PLACE_KEEPOUT      UNOWNED
BOTTOM 2.00000        
         0            75.25000           120.00000             0.00000
         0            84.75000           120.00000          -180.00000
         0            75.25000           120.00000          -180.00000
.END_PLACE_KEEPOUT
.PLACE_KEEPOUT      UNOWNED
BOTTOM 2.00000        
         0            73.80000           105.05000             0.00000
         0            83.30000           105.05000          -180.00000
         0            73.80000           105.05000          -180.00000
.END_PLACE_KEEPOUT
.PLACE_KEEPOUT      UNOWNED
BOTTOM 2.00000        
         0            18.15000           105.05000             0.00000
         0            27.65000           105.05000          -180.00000
         0            18.15000           105.05000          -180.00000
.END_PLACE_KEEPOUT
.PLACE_KEEPOUT      UNOWNED
BOTTOM 2.00000        
         0            18.05000            60.55000             0.00000
         0            27.55000            60.55000          -180.00000
         0            18.05000            60.55000          -180.00000
.END_PLACE_KEEPOUT
.PLACE_KEEPOUT      UNOWNED
BOTTOM 2.00000        
         0            13.25000            25.00000             0.00000
         0            22.75000            25.00000          -180.00000
         0            13.25000            25.00000          -180.00000
.END_PLACE_KEEPOUT
.PLACE_KEEPOUT      UNOWNED
BOTTOM 2.00000        
         0            73.75000            40.05000             0.00000
         0            83.25000            40.05000          -180.00000
         0            73.75000            40.05000          -180.00000
.END_PLACE_KEEPOUT
.PLACE_KEEPOUT      UNOWNED
BOTTOM 2.00000        
         0            98.25000            10.00000             0.00000
         0           107.75000            10.00000          -180.00000
         0            98.25000            10.00000          -180.00000
.END_PLACE_KEEPOUT
.PLACE_KEEPOUT      UNOWNED
BOTTOM 2.00000        
         0           121.66510            34.85500             0.00000
         0           126.66510            34.85500          -180.00000
         0           121.66510            34.85500          -180.00000
.END_PLACE_KEEPOUT
.PLACE_KEEPOUT      UNOWNED
BOTTOM 2.00000        
         0           125.37010            41.84500             0.00000
         0           122.96010            41.84500          -180.00000
         0           125.37010            41.84500          -180.00000
.END_PLACE_KEEPOUT
.PLACE_KEEPOUT      UNOWNED
BOTTOM 2.00000        
         0           162.80000            45.72000             0.00000
         0           168.80000            45.72000          -180.00000
         0           162.80000            45.72000          -180.00000
.END_PLACE_KEEPOUT
.PLACE_KEEPOUT      UNOWNED
BOTTOM 2.00000        
         0           216.80000            84.48000             0.00000
         0           222.80000            84.48000          -180.00000
         0           216.80000            84.48000          -180.00000
.END_PLACE_KEEPOUT
.PLACE_KEEPOUT      UNOWNED
BOTTOM 2.00000        
         0           150.75000           110.00000             0.00000
         0           160.25000           110.00000          -180.00000
         0           150.75000           110.00000          -180.00000
.END_PLACE_KEEPOUT
.PLACE_KEEPOUT      UNOWNED
BOTTOM 2.00000        
         0           217.75000           110.00000             0.00000
         0           227.25000           110.00000          -180.00000
         0           217.75000           110.00000          -180.00000
.END_PLACE_KEEPOUT
.PLACE_KEEPOUT      UNOWNED
BOTTOM 2.00000        
         0            13.25000           120.00000             0.00000
         0            22.75000           120.00000          -180.00000
         0            13.25000           120.00000          -180.00000
.END_PLACE_KEEPOUT
.PLACE_KEEPOUT      UNOWNED
BOTTOM 2.00000        
         0            37.70000           170.00000             0.00000
         0            45.20000           170.00000          -180.00000
         0            37.70000           170.00000          -180.00000
.END_PLACE_KEEPOUT
.ROUTE_KEEPOUT  UNOWNED
TOP
         0            87.75000           188.00000             0.00000
         0            97.25000           188.00000           180.00000
         0            87.75000           188.00000           180.00000
.END_ROUTE_KEEPOUT
.ROUTE_KEEPOUT  UNOWNED
TOP
         0             7.75000           188.00000             0.00000
         0            17.25000           188.00000           180.00000
         0             7.75000           188.00000           180.00000
.END_ROUTE_KEEPOUT
.ROUTE_KEEPOUT  UNOWNED
TOP
         0            37.70000           170.00000             0.00000
         0            45.20000           170.00000           180.00000
         0            37.70000           170.00000           180.00000
.END_ROUTE_KEEPOUT
.ROUTE_KEEPOUT  UNOWNED
TOP
         0           150.75000           188.00000             0.00000
         0           160.25000           188.00000           180.00000
         0           150.75000           188.00000           180.00000
.END_ROUTE_KEEPOUT
.ROUTE_KEEPOUT  UNOWNED
TOP
         0           217.75000           188.00000             0.00000
         0           227.25000           188.00000           180.00000
         0           217.75000           188.00000           180.00000
.END_ROUTE_KEEPOUT
.ROUTE_KEEPOUT  UNOWNED
TOP
         0            75.25000           120.00000             0.00000
         0            84.75000           120.00000           180.00000
         0            75.25000           120.00000           180.00000
.END_ROUTE_KEEPOUT
.ROUTE_KEEPOUT  UNOWNED
TOP
         0            11.90000           109.80000             0.00000
         0            11.90000           103.80000             0.00000
         0            18.31742           103.80000             0.00000
         0            22.90000           109.80000           254.74248
         0            11.90000           109.80000             0.00000
.END_ROUTE_KEEPOUT
.ROUTE_KEEPOUT  UNOWNED
TOP
         0            78.55000           109.80000             0.00000
         0            92.70000           109.80000             0.00000
         0            92.70000           100.30000             0.00000
         0            78.55000           100.30000             0.00000
         0            78.55000           109.80000          -180.00000
.END_ROUTE_KEEPOUT
.ROUTE_KEEPOUT  UNOWNED
TOP
         0            22.80000            55.80000             0.00000
         0             8.65000            55.80000             0.00000
         0             8.65000            65.30000             0.00000
         0            22.80000            65.30000             0.00000
         0            22.80000            55.80000          -180.00000
.END_ROUTE_KEEPOUT
.ROUTE_KEEPOUT  UNOWNED
TOP
         0            22.75000            25.00000             0.00000
         0            13.25000            25.00000           180.00000
         0            22.75000            25.00000           180.00000
.END_ROUTE_KEEPOUT
.ROUTE_KEEPOUT  UNOWNED
TOP
         0            78.50000            44.80000             0.00000
         0            89.50000            44.80000             0.00000
         0            89.50000            35.30000             0.00000
         0            78.50000            35.30000             0.00000
         0            78.50000            44.80000          -180.00000
.END_ROUTE_KEEPOUT
.ROUTE_KEEPOUT  UNOWNED
TOP
         0           107.75000            10.00000             0.00000
         0            98.25000            10.00000           180.00000
         0           107.75000            10.00000           180.00000
.END_ROUTE_KEEPOUT
.ROUTE_KEEPOUT  UNOWNED
TOP
         0           227.25000            15.00000             0.00000
         0           217.75000            15.00000           180.00000
         0           227.25000            15.00000           180.00000
.END_ROUTE_KEEPOUT
.ROUTE_KEEPOUT  UNOWNED
TOP
         0           216.80000            84.48000             0.00000
         0           222.80000            84.48000           180.00000
         0           216.80000            84.48000           180.00000
.END_ROUTE_KEEPOUT
.ROUTE_KEEPOUT  UNOWNED
TOP
         0           162.80000            45.72000             0.00000
         0           168.80000            45.72000           180.00000
         0           162.80000            45.72000           180.00000
.END_ROUTE_KEEPOUT
.ROUTE_KEEPOUT  UNOWNED
TOP
         0           160.25000           110.00000             0.00000
         0           150.75000           110.00000           180.00000
         0           160.25000           110.00000           180.00000
.END_ROUTE_KEEPOUT
.ROUTE_KEEPOUT  UNOWNED
TOP
         0           227.25000           110.00000             0.00000
         0           217.75000           110.00000           180.00000
         0           227.25000           110.00000           180.00000
.END_ROUTE_KEEPOUT
.ROUTE_KEEPOUT  UNOWNED
TOP
         0            13.25000           120.00000             0.00000
         0            22.75000           120.00000           180.00000
         0            13.25000           120.00000           180.00000
.END_ROUTE_KEEPOUT
.ROUTE_KEEPOUT  UNOWNED
BOTTOM
         0            97.25000           188.00000             0.00000
         0            87.75000           188.00000          -180.00000
         0            97.25000           188.00000          -180.00000
.END_ROUTE_KEEPOUT
.ROUTE_KEEPOUT  UNOWNED
BOTTOM
         0            17.25000           188.00000             0.00000
         0             7.75000           188.00000          -180.00000
         0            17.25000           188.00000          -180.00000
.END_ROUTE_KEEPOUT
.ROUTE_KEEPOUT  UNOWNED
BOTTOM
         0            84.75000           120.00000             0.00000
         0            75.25000           120.00000          -180.00000
         0            84.75000           120.00000          -180.00000
.END_ROUTE_KEEPOUT
.ROUTE_KEEPOUT  UNOWNED
BOTTOM
         0            83.30000           105.05000             0.00000
         0            73.80000           105.05000          -180.00000
         0            83.30000           105.05000          -180.00000
.END_ROUTE_KEEPOUT
.ROUTE_KEEPOUT  UNOWNED
BOTTOM
         0            27.65000           105.05000             0.00000
         0            18.15000           105.05000          -180.00000
         0            27.65000           105.05000          -180.00000
.END_ROUTE_KEEPOUT
.ROUTE_KEEPOUT  UNOWNED
BOTTOM
         0            27.55000            60.55000             0.00000
         0            18.05000            60.55000          -180.00000
         0            27.55000            60.55000          -180.00000
.END_ROUTE_KEEPOUT
.ROUTE_KEEPOUT  UNOWNED
BOTTOM
         0            22.75000            25.00000             0.00000
         0            13.25000            25.00000          -180.00000
         0            22.75000            25.00000          -180.00000
.END_ROUTE_KEEPOUT
.ROUTE_KEEPOUT  UNOWNED
BOTTOM
         0            83.25000            40.05000             0.00000
         0            73.75000            40.05000          -180.00000
         0            83.25000            40.05000          -180.00000
.END_ROUTE_KEEPOUT
.ROUTE_KEEPOUT  UNOWNED
BOTTOM
         0           107.75000            10.00000             0.00000
         0            98.25000            10.00000          -180.00000
         0           107.75000            10.00000          -180.00000
.END_ROUTE_KEEPOUT
.ROUTE_KEEPOUT  UNOWNED
BOTTOM
         0           126.66510            34.85500             0.00000
         0           121.66510            34.85500          -180.00000
         0           126.66510            34.85500          -180.00000
.END_ROUTE_KEEPOUT
.ROUTE_KEEPOUT  UNOWNED
BOTTOM
         0           162.50000            14.70000             0.00000
         0           157.50000            14.70000          -180.00000
         0           162.50000            14.70000          -180.00000
.END_ROUTE_KEEPOUT
.ROUTE_KEEPOUT  UNOWNED
BOTTOM
         0           182.50000            14.70000             0.00000
         0           177.50000            14.70000          -180.00000
         0           182.50000            14.70000          -180.00000
.END_ROUTE_KEEPOUT
.ROUTE_KEEPOUT  UNOWNED
BOTTOM
         0           227.25000            15.00000             0.00000
         0           217.75000            15.00000          -180.00000
         0           227.25000            15.00000          -180.00000
.END_ROUTE_KEEPOUT
.ROUTE_KEEPOUT  UNOWNED
BOTTOM
         0           227.25000           188.00000             0.00000
         0           217.75000           188.00000          -180.00000
         0           227.25000           188.00000          -180.00000
.END_ROUTE_KEEPOUT
.ROUTE_KEEPOUT  UNOWNED
BOTTOM
         0           160.25000           188.00000             0.00000
         0           150.75000           188.00000          -180.00000
         0           160.25000           188.00000          -180.00000
.END_ROUTE_KEEPOUT
.ROUTE_KEEPOUT  UNOWNED
BOTTOM
         0            45.20000           170.00000             0.00000
         0            37.70000           170.00000          -180.00000
         0            45.20000           170.00000          -180.00000
.END_ROUTE_KEEPOUT
.ROUTE_KEEPOUT  UNOWNED
BOTTOM
         0           168.80000            45.72000             0.00000
         0           162.80000            45.72000          -180.00000
         0           168.80000            45.72000          -180.00000
.END_ROUTE_KEEPOUT
.ROUTE_KEEPOUT  UNOWNED
BOTTOM
         0           222.80000            84.48000             0.00000
         0           216.80000            84.48000          -180.00000
         0           222.80000            84.48000          -180.00000
.END_ROUTE_KEEPOUT
.ROUTE_KEEPOUT  UNOWNED
BOTTOM
         0            22.75000           120.00000             0.00000
         0            13.25000           120.00000          -180.00000
         0            22.75000           120.00000          -180.00000
.END_ROUTE_KEEPOUT
.ROUTE_KEEPOUT  UNOWNED
BOTTOM
         0           227.25000           110.00000             0.00000
         0           217.75000           110.00000          -180.00000
         0           227.25000           110.00000          -180.00000
.END_ROUTE_KEEPOUT
.ROUTE_KEEPOUT  UNOWNED
BOTTOM
         0           160.25000           110.00000             0.00000
         0           150.75000           110.00000          -180.00000
         0           160.25000           110.00000          -180.00000
.END_ROUTE_KEEPOUT
.PLACEMENT
020_80818_0001 020_80818_0001 CN1           
141.30000      44.20000       0.00000        180.00000      TOP       PLACED         
19-000387$AA   19-000387$AA   U1            
192.80000      65.10000       0.00000        180.00000      TOP       PLACED         
071_02500_0B0U 071_02500_0B0U U2            
47.70000       145.00000      0.00000        270.00000      TOP       PLACED         
20_F1354_120   20_F1354_120   MEZZ1         
77.70000       72.55000       0.00000        270.00000      TOP       PLACED         
020_80074_0036 020_80074_0036 EXT1          
180.00000      14.70000       0.00000        0.00000        TOP       PLACED         
020_80074_0036 020_80074_0036 EXT2          
160.00000      14.70000       0.00000        0.00000        TOP       PLACED         
022_40001_0221 022_40001_0221 PWR1          
24.00000       8.75000        0.00000        0.00000        TOP       PLACED         
022_10005_0I61 022_10005_0I61 USB1          
88.90000       12.65000       0.00000        0.00000        TOP       PLACED         
022_40001_0681 022_40001_0681 RST1          
12.00000       6.25000        0.00000        0.00000        TOP       PLACED         
020_F0528_0011 020_F0528_0011 TPM1          
54.28000       172.70000      0.00000        0.00000        TOP       PLACED         
087_71242_0465 087_71242_0465 NUT1          
41.45000       170.00000      0.00000        0.00000        TOP       PLACED         
06_WP130_14A   06_WP130_14A   LED2          
194.00000      6.20000        0.00000        0.00000        TOP       PLACED         
06_WP130_14A   06_WP130_14A   LED3          
146.00000      6.20000        0.00000        0.00000        TOP       PLACED         
06_WP130_14A   06_WP130_14A   LED7          
206.00000      6.20000        0.00000        0.00000        TOP       PLACED         
.END_PLACEMENT

